(kicad_pcb
	(version 20241229)
	(generator "pcbnew")
	(generator_version "9.0")
	(general
		(thickness 1.294)
		(legacy_teardrops no)
	)
	(paper "A3")
	(title_block
		(title "Kintex 410T devboard")
		(date "2024-04-03")
		(rev "1.1.2")
		(comment 9 "footprints 302-307 of 975")
	)
	(layers
		(0 "F.Cu" mixed)
		(4 "In1.Cu" power)
		(6 "In2.Cu" power)
		(8 "In3.Cu" mixed)
		(10 "In4.Cu" power)
		(12 "In5.Cu" mixed)
		(14 "In6.Cu" power)
		(16 "In7.Cu" mixed)
		(18 "In8.Cu" power)
		(2 "B.Cu" mixed)
		(9 "F.Adhes" user "F.Adhesive")
		(11 "B.Adhes" user "B.Adhesive")
		(13 "F.Paste" user)
		(15 "B.Paste" user)
		(5 "F.SilkS" user "F.Silkscreen")
		(7 "B.SilkS" user "B.Silkscreen")
		(1 "F.Mask" user)
		(3 "B.Mask" user)
		(17 "Dwgs.User" user "User.Drawings")
		(19 "Cmts.User" user "User.Comments")
		(21 "Eco1.User" user "User.Eco1")
		(23 "Eco2.User" user "User.Eco2")
		(25 "Edge.Cuts" user)
		(27 "Margin" user)
		(31 "F.CrtYd" user "F.Courtyard")
		(29 "B.CrtYd" user "B.Courtyard")
		(35 "F.Fab" user)
		(33 "B.Fab" user)
	)
	(footprint "antmicro-footprints:XDFN4"
		(layer "F.Cu")
		(at 152.5 146.65 -90)
		(property "Reference" "U38"
			(at -0.85 -0.4 90)
			(layer "F.SilkS")
			(effects
				(font
					(size 0.7 0.7)
					(thickness 0.15)
				)
				(justify left bottom)
			)
		)
		(property "Value" "TPS7A20185PDQNR"
			(at -1.73 1.92 270)
			(layer "F.Fab")
			(effects
				(font
					(size 0.7 0.7)
					(thickness 0.15)
				)
				(justify left bottom)
			)
		)
		(property "Description" "Linear voltage regulator"
			(at 0 0 270)
			(layer "F.Fab")
			(hide yes)
			(effects
				(font
					(size 1.27 1.27)
					(thickness 0.15)
				)
			)
		)
		(property "Author" "Antmicro"
			(at 5.85 299.15 0)
			(layer "F.Fab")
			(hide yes)
			(effects
				(font
					(size 1 1)
					(thickness 0.15)
				)
			)
		)
		(property "License" "Apache-2.0"
			(at 5.85 299.15 0)
			(layer "F.Fab")
			(hide yes)
			(effects
				(font
					(size 1 1)
					(thickness 0.15)
				)
			)
		)
		(property "MPN" "TPS7A20185PDQNR"
			(at 5.85 299.15 0)
			(layer "F.Fab")
			(hide yes)
			(effects
				(font
					(size 1 1)
					(thickness 0.15)
				)
			)
		)
		(property "Manufacturer" "Texas Instruments"
			(at 5.85 299.15 0)
			(layer "F.Fab")
			(hide yes)
			(effects
				(font
					(size 1 1)
					(thickness 0.15)
				)
			)
		)
		(sheetname "DC-DC Converters")
		(sheetfile "dc-dc.kicad_sch")
		(attr smd)
		(fp_circle
			(center -0.75 -0.6)
			(end -0.699 -0.6)
			(stroke
				(width 0.15)
				(type solid)
			)
			(fill yes)
			(layer "F.SilkS")
		)
		(fp_poly
			(pts
				(xy -0.152 -0.152) (xy 0.15 -0.152) (xy 0.15 0.15) (xy -0.152 0.15)
			)
			(stroke
				(width 0.01)
				(type solid)
			)
			(fill yes)
			(layer "F.Paste")
		)
		(fp_poly
			(pts
				(xy -0.652 -0.452) (xy -0.18 -0.452) (xy -0.43 -0.202) (xy -0.652 -0.202)
			)
			(stroke
				(width 0.01)
				(type solid)
			)
			(fill yes)
			(layer "F.Paste")
		)
		(fp_poly
			(pts
				(xy -0.652 0.45) (xy -0.25 0.45) (xy -0.25 0.378) (xy -0.43 0.2) (xy -0.652 0.2)
			)
			(stroke
				(width 0.01)
				(type solid)
			)
			(fill yes)
			(layer "F.Paste")
		)
		(fp_poly
			(pts
				(xy 0.65 0.45) (xy 0.248 0.45) (xy 0.248 0.378) (xy 0.428 0.2) (xy 0.65 0.2)
			)
			(stroke
				(width 0.01)
				(type solid)
			)
			(fill yes)
			(layer "F.Paste")
		)
		(fp_poly
			(pts
				(xy 0.65 -0.452) (xy 0.248 -0.452) (xy 0.248 -0.38) (xy 0.428 -0.202) (xy 0.65 -0.202)
			)
			(stroke
				(width 0.01)
				(type solid)
			)
			(fill yes)
			(layer "F.Paste")
		)
		(fp_rect
			(start -0.8 -0.8)
			(end 0.8 0.8)
			(stroke
				(width 0.05)
				(type solid)
			)
			(fill no)
			(layer "F.CrtYd")
		)
		(fp_line
			(start -0.5 -0.3)
			(end -0.3 -0.5)
			(stroke
				(width 0.15)
				(type solid)
			)
			(layer "F.Fab")
		)
		(fp_rect
			(start -0.5 -0.5)
			(end 0.498 0.498)
			(stroke
				(width 0.15)
				(type solid)
			)
			(fill no)
			(layer "F.Fab")
		)
		(pad "1" smd custom
			(at -0.452 -0.327 270)
			(size 0.1 0.1)
			(layers "F.Cu")
			(net 747 "/DC-DC Converters/1V85_OUT")
			(pinfunction "VOUT")
			(pintype "power_out")
			(zone_connect 2)
			(options
				(clearance outline)
				(anchor rect)
			)
			(primitives
				(gr_poly
					(pts
						(xy -0.2 -0.125) (xy 0.27 -0.125) (xy 0.02 0.125) (xy -0.2 0.125)
					)
					(width 0.01)
					(fill yes)
				)
			)
		)
		(pad "2" smd custom
			(at -0.452 0.325 270)
			(size 0.1 0.1)
			(layers "F.Cu")
			(net 1 "GND")
			(pinfunction "GND")
			(pintype "power_in")
			(zone_connect 2)
			(options
				(clearance outline)
				(anchor rect)
			)
			(primitives
				(gr_poly
					(pts
						(xy -0.2 0.125) (xy 0.2 0.125) (xy 0.2 0.055) (xy 0.02 -0.125) (xy -0.2 -0.125)
					)
					(width 0.01)
					(fill yes)
				)
			)
		)
		(pad "3" smd custom
			(at 0.45 0.325 270)
			(size 0.1 0.1)
			(layers "F.Cu")
			(net 742 "/DC-DC Converters/1V85_VIN")
			(pinfunction "EN")
			(pintype "input")
			(zone_connect 2)
			(options
				(clearance outline)
				(anchor rect)
			)
			(primitives
				(gr_poly
					(pts
						(xy 0.2 0.125) (xy -0.2 0.125) (xy -0.2 0.055) (xy -0.02 -0.125) (xy 0.2 -0.125)
					)
					(width 0.01)
					(fill yes)
				)
			)
		)
		(pad "4" smd custom
			(at 0.45 -0.327 270)
			(size 0.1 0.1)
			(layers "F.Cu")
			(net 742 "/DC-DC Converters/1V85_VIN")
			(pinfunction "VIN")
			(pintype "input")
			(zone_connect 2)
			(options
				(clearance outline)
				(anchor rect)
			)
			(primitives
				(gr_poly
					(pts
						(xy 0.2 -0.125) (xy -0.2 -0.125) (xy -0.2 -0.055) (xy -0.02 0.125) (xy 0.2 0.125)
					)
					(width 0.01)
					(fill yes)
				)
			)
		)
		(pad "5" smd rect
			(at 0 0 315)
			(size 0.48 0.48)
			(layers "F.Cu" "F.Mask")
			(net 1 "GND")
			(pinfunction "EXP")
			(pintype "passive")
			(zone_connect 2)
		)
	)
	(footprint "antmicro-footprints:NetTie-2_SMD_Pad0.127mm"
		(layer "F.Cu")
		(at 247.3 143.602 90)
		(descr "Net tie, 2 pin, 0.127mm  SMD pads")
		(tags "net tie")
		(property "Reference" "NT21"
			(at -0.128 -1.345 90)
			(layer "F.SilkS")
			(hide yes)
			(effects
				(font
					(size 0.7 0.7)
					(thickness 0.15)
				)
				(justify left bottom)
			)
		)
		(property "Value" "Net-Tie_2"
			(at 0 1.199 90)
			(layer "F.Fab")
			(effects
				(font
					(size 0.7 0.7)
					(thickness 0.15)
				)
				(justify left bottom)
			)
		)
		(property "Description" "Net tie, 2 pins"
			(at 0 0 90)
			(layer "F.Fab")
			(hide yes)
			(effects
				(font
					(size 1.27 1.27)
					(thickness 0.15)
				)
			)
		)
		(property "Author" "Antmicro"
			(at 390.902 -103.698 0)
			(layer "F.Fab")
			(hide yes)
			(effects
				(font
					(size 1 1)
					(thickness 0.15)
				)
			)
		)
		(property "License" "Apache-2.0"
			(at 390.902 -103.698 0)
			(layer "F.Fab")
			(hide yes)
			(effects
				(font
					(size 1 1)
					(thickness 0.15)
				)
			)
		)
		(property "MPN" ""
			(at 390.902 -103.698 0)
			(layer "F.Fab")
			(hide yes)
			(effects
				(font
					(size 1 1)
					(thickness 0.15)
				)
			)
		)
		(property "Manufacturer" ""
			(at 390.902 -103.698 0)
			(layer "F.Fab")
			(hide yes)
			(effects
				(font
					(size 1 1)
					(thickness 0.15)
				)
			)
		)
		(sheetname "FPGA Config")
		(sheetfile "fpga-config.kicad_sch")
		(attr exclude_from_pos_files)
		(net_tie_pad_groups "1, 2")
		(fp_poly
			(pts
				(xy -0.0635 -0.0635) (xy 0.0625 -0.0635) (xy 0.0625 0.0635) (xy -0.0635 0.0635)
			)
			(stroke
				(width 0)
				(type solid)
			)
			(fill yes)
			(layer "F.Cu")
		)
		(pad "1" smd roundrect
			(at -0.127 0 270)
			(size 0.127 0.127)
			(layers "F.Cu")
			(roundrect_rratio 0.5)
			(chamfer_ratio 0)
			(chamfer top_left bottom_left)
			(net 1335 "/SUP_MCU.TEMP_ALERT_N")
			(pinfunction "1")
			(pintype "passive")
		)
		(pad "2" smd roundrect
			(at 0.126 0 90)
			(size 0.127 0.127)
			(layers "F.Cu")
			(roundrect_rratio 0.5)
			(chamfer_ratio 0)
			(chamfer top_left bottom_left)
			(net 113 "/FPGA Config/TEMP_~{ALERT}")
			(pinfunction "2")
			(pintype "passive")
		)
	)
	(footprint "antmicro-footprints:C_0402_1005Metric"
		(layer "F.Cu")
		(at 173.570001 109.016251 180)
		(descr "Capacitor SMD 0402")
		(tags "capacitor SMD 0402")
		(property "Reference" "C301"
			(at -3.729999 -0.383749 0)
			(layer "F.SilkS")
			(effects
				(font
					(size 0.7 0.7)
					(thickness 0.15)
				)
				(justify right bottom)
			)
		)
		(property "Value" "C_100n_0402"
			(at 0 1.4 0)
			(layer "F.Fab")
			(effects
				(font
					(size 0.7 0.7)
					(thickness 0.15)
				)
				(justify right bottom)
			)
		)
		(property "Description" "SMD Multilayer Ceramic Capacitor, 0.1 µF, 50 V, 0402 [1005 Metric], ± 10%, X5R, GRM Series"
			(at 0 0 180)
			(layer "F.Fab")
			(hide yes)
			(effects
				(font
					(size 1.27 1.27)
					(thickness 0.15)
				)
			)
		)
		(property "Author" "Antmicro"
			(at 347.140002 218.032502 0)
			(layer "F.Fab")
			(hide yes)
			(effects
				(font
					(size 1 1)
					(thickness 0.15)
				)
			)
		)
		(property "Dielectric" "X5R"
			(at 347.140002 218.032502 0)
			(layer "F.Fab")
			(hide yes)
			(effects
				(font
					(size 1 1)
					(thickness 0.15)
				)
			)
		)
		(property "License" "Apache-2.0"
			(at 347.140002 218.032502 0)
			(layer "F.Fab")
			(hide yes)
			(effects
				(font
					(size 1 1)
					(thickness 0.15)
				)
			)
		)
		(property "MPN" "GRM155R61H104KE14D"
			(at 347.140002 218.032502 0)
			(layer "F.Fab")
			(hide yes)
			(effects
				(font
					(size 1 1)
					(thickness 0.15)
				)
			)
		)
		(property "Manufacturer" "Murata"
			(at 347.140002 218.032502 0)
			(layer "F.Fab")
			(hide yes)
			(effects
				(font
					(size 1 1)
					(thickness 0.15)
				)
			)
		)
		(property "Val" "100n"
			(at 347.140002 218.032502 0)
			(layer "F.Fab")
			(hide yes)
			(effects
				(font
					(size 1 1)
					(thickness 0.15)
				)
			)
		)
		(property "Voltage" "50V"
			(at 347.140002 218.032502 0)
			(layer "F.Fab")
			(hide yes)
			(effects
				(font
					(size 1 1)
					(thickness 0.15)
				)
			)
		)
		(sheetname "FMC+ HSPC")
		(sheetfile "fmc-hspc.kicad_sch")
		(attr smd)
		(fp_rect
			(start -0.925 -0.47)
			(end 0.925 0.47)
			(stroke
				(width 0.05)
				(type default)
			)
			(fill no)
			(layer "F.CrtYd")
		)
		(fp_line
			(start 0.504 0.248)
			(end -0.494 0.248)
			(stroke
				(width 0.15)
				(type solid)
			)
			(layer "F.Fab")
		)
		(fp_line
			(start 0.504 -0.25)
			(end 0.504 0.248)
			(stroke
				(width 0.15)
				(type solid)
			)
			(layer "F.Fab")
		)
		(fp_line
			(start -0.494 0.248)
			(end -0.494 -0.25)
			(stroke
				(width 0.15)
				(type solid)
			)
			(layer "F.Fab")
		)
		(fp_line
			(start -0.494 -0.25)
			(end 0.504 -0.25)
			(stroke
				(width 0.15)
				(type solid)
			)
			(layer "F.Fab")
		)
		(pad "1" smd roundrect
			(at -0.48 0 180)
			(size 0.59 0.64)
			(layers "F.Cu" "F.Mask" "F.Paste")
			(roundrect_rratio 0.25)
			(net 69 "/FMC+ HSPC/GTX116.TX2_N")
			(pintype "passive")
		)
		(pad "2" smd roundrect
			(at 0.48 0 180)
			(size 0.59 0.64)
			(layers "F.Cu" "F.Mask" "F.Paste")
			(roundrect_rratio 0.25)
			(net 67 "/FMC+ HSPC/GTX_TX1_C_N")
			(pintype "passive")
		)
	)
	(footprint "antmicro-footprints:R_0402_1005Metric"
		(layer "F.Cu")
		(at 259.6 130.7)
		(descr "Resistor SMD 0402")
		(tags "resistor SMD 0402")
		(property "Reference" "R191"
			(at -1.05 -6.1 0)
			(layer "F.SilkS")
			(effects
				(font
					(size 0.7 0.7)
					(thickness 0.15)
				)
				(justify left bottom)
			)
		)
		(property "Value" "R_10k_0402"
			(at 0 1.4 0)
			(layer "F.Fab")
			(effects
				(font
					(size 0.7 0.7)
					(thickness 0.15)
				)
				(justify left bottom)
			)
		)
		(property "Description" "SMD Chip Resistor, 10 kohm, ± 1%, 62.5 mW, 0402 [1005 Metric], Thick Film, General Purpose"
			(at 0 0 0)
			(layer "F.Fab")
			(hide yes)
			(effects
				(font
					(size 1.27 1.27)
					(thickness 0.15)
				)
			)
		)
		(property "Author" "Antmicro"
			(at 0 0 0)
			(layer "F.Fab")
			(hide yes)
			(effects
				(font
					(size 1 1)
					(thickness 0.15)
				)
			)
		)
		(property "License" "Apache-2.0"
			(at 0 0 0)
			(layer "F.Fab")
			(hide yes)
			(effects
				(font
					(size 1 1)
					(thickness 0.15)
				)
			)
		)
		(property "MPN" "CR0402-FX-1002GLF"
			(at 0 0 0)
			(layer "F.Fab")
			(hide yes)
			(effects
				(font
					(size 1 1)
					(thickness 0.15)
				)
			)
		)
		(property "Manufacturer" "Bourns"
			(at 0 0 0)
			(layer "F.Fab")
			(hide yes)
			(effects
				(font
					(size 1 1)
					(thickness 0.15)
				)
			)
		)
		(property "Tolerance" "1%"
			(at 0 0 0)
			(layer "F.Fab")
			(hide yes)
			(effects
				(font
					(size 1 1)
					(thickness 0.15)
				)
			)
		)
		(property "Val" "10k"
			(at 0 0 0)
			(layer "F.Fab")
			(hide yes)
			(effects
				(font
					(size 1 1)
					(thickness 0.15)
				)
			)
		)
		(sheetname "USB PHY")
		(sheetfile "usb-phy.kicad_sch")
		(attr smd)
		(fp_rect
			(start -0.925 -0.47)
			(end 0.925 0.47)
			(stroke
				(width 0.05)
				(type default)
			)
			(fill no)
			(layer "F.CrtYd")
		)
		(fp_rect
			(start -0.5 -0.25)
			(end 0.5 0.25)
			(stroke
				(width 0.15)
				(type solid)
			)
			(fill no)
			(layer "F.Fab")
		)
		(pad "1" smd roundrect
			(at -0.48 0)
			(size 0.59 0.64)
			(layers "F.Cu" "F.Mask" "F.Paste")
			(roundrect_rratio 0.25)
			(net 943 "Net-(R191-Pad1)")
			(pintype "passive")
		)
		(pad "2" smd roundrect
			(at 0.48 0)
			(size 0.59 0.64)
			(layers "F.Cu" "F.Mask" "F.Paste")
			(roundrect_rratio 0.25)
			(net 497 "/FPGA Bank 12 & 13/USB_USER.VDET")
			(pintype "passive")
		)
	)
	(footprint "antmicro-footprints:C_0402_1005Metric"
		(layer "F.Cu")
		(at 245.099 118.904)
		(descr "Capacitor SMD 0402")
		(tags "capacitor SMD 0402")
		(property "Reference" "C397"
			(at -1.949 1.246 0)
			(layer "F.SilkS")
			(effects
				(font
					(size 0.7 0.7)
					(thickness 0.15)
				)
				(justify left bottom)
			)
		)
		(property "Value" "C_10u_0402"
			(at 0 1.4 0)
			(layer "F.Fab")
			(effects
				(font
					(size 0.7 0.7)
					(thickness 0.15)
				)
				(justify left bottom)
			)
		)
		(property "Description" "SMD Multilayer Ceramic Capacitor, 10 µF, 6.3 V, 0402 [1005 Metric], ± 20%, X5R, CC Series"
			(at 0 0 0)
			(layer "F.Fab")
			(hide yes)
			(effects
				(font
					(size 1.27 1.27)
					(thickness 0.15)
				)
			)
		)
		(property "Author" "Antmicro"
			(at 0 0 0)
			(layer "F.Fab")
			(hide yes)
			(effects
				(font
					(size 1 1)
					(thickness 0.15)
				)
			)
		)
		(property "Dielectric" ""
			(at 0 0 0)
			(layer "F.Fab")
			(hide yes)
			(effects
				(font
					(size 1 1)
					(thickness 0.15)
				)
			)
		)
		(property "License" "Apache-2.0"
			(at 0 0 0)
			(layer "F.Fab")
			(hide yes)
			(effects
				(font
					(size 1 1)
					(thickness 0.15)
				)
			)
		)
		(property "MPN" "CC0402MRX5R5BB106"
			(at 0 0 0)
			(layer "F.Fab")
			(hide yes)
			(effects
				(font
					(size 1 1)
					(thickness 0.15)
				)
			)
		)
		(property "Manufacturer" "YAGEO"
			(at 0 0 0)
			(layer "F.Fab")
			(hide yes)
			(effects
				(font
					(size 1 1)
					(thickness 0.15)
				)
			)
		)
		(property "Val" "10u"
			(at 0 0 0)
			(layer "F.Fab")
			(hide yes)
			(effects
				(font
					(size 1 1)
					(thickness 0.15)
				)
			)
		)
		(property "Voltage" ""
			(at 0 0 0)
			(layer "F.Fab")
			(hide yes)
			(effects
				(font
					(size 1 1)
					(thickness 0.15)
				)
			)
		)
		(sheetname "USB PHY")
		(sheetfile "usb-phy.kicad_sch")
		(attr smd)
		(fp_rect
			(start -0.925 -0.47)
			(end 0.925 0.47)
			(stroke
				(width 0.05)
				(type default)
			)
			(fill no)
			(layer "F.CrtYd")
		)
		(fp_line
			(start -0.494 -0.25)
			(end 0.504 -0.25)
			(stroke
				(width 0.15)
				(type solid)
			)
			(layer "F.Fab")
		)
		(fp_line
			(start -0.494 0.248)
			(end -0.494 -0.25)
			(stroke
				(width 0.15)
				(type solid)
			)
			(layer "F.Fab")
		)
		(fp_line
			(start 0.504 -0.25)
			(end 0.504 0.248)
			(stroke
				(width 0.15)
				(type solid)
			)
			(layer "F.Fab")
		)
		(fp_line
			(start 0.504 0.248)
			(end -0.494 0.248)
			(stroke
				(width 0.15)
				(type solid)
			)
			(layer "F.Fab")
		)
		(pad "1" smd roundrect
			(at -0.48 0)
			(size 0.59 0.64)
			(layers "F.Cu" "F.Mask" "F.Paste")
			(roundrect_rratio 0.25)
			(net 1 "GND")
			(pintype "passive")
		)
		(pad "2" smd roundrect
			(at 0.48 0)
			(size 0.59 0.64)
			(layers "F.Cu" "F.Mask" "F.Paste")
			(roundrect_rratio 0.25)
			(net 715 "/USB PHY/USB_USR_VBUS")
			(pintype "passive")
		)
	)
	(footprint "antmicro-footprints:MP_Pad6mm_Drill3mm"
		(layer "F.Cu")
		(at 153.5 73.5)
		(property "Reference" "MH4"
			(at -0.178 4.025 0)
			(layer "F.SilkS")
			(hide yes)
			(effects
				(font
					(size 0.7 0.7)
					(thickness 0.15)
				)
				(justify left bottom)
			)
		)
		(property "Value" "MP_Pad6mm_Drill3mm"
			(at -0.153 -4.153 0)
			(layer "F.Fab")
			(effects
				(font
					(size 0.7 0.7)
					(thickness 0.15)
				)
				(justify left bottom)
			)
		)
		(property "Description" "Mechanical part"
			(at 0 0 0)
			(layer "F.Fab")
			(hide yes)
			(effects
				(font
					(size 1.27 1.27)
					(thickness 0.15)
				)
			)
		)
		(property "Author" "Antmicro"
			(at 0 0 0)
			(layer "F.Fab")
			(hide yes)
			(effects
				(font
					(size 1 1)
					(thickness 0.15)
				)
			)
		)
		(property "License" "Apache-2.0"
			(at 0 0 0)
			(layer "F.Fab")
			(hide yes)
			(effects
				(font
					(size 1 1)
					(thickness 0.15)
				)
			)
		)
		(property "MPN" ""
			(at 0 0 0)
			(layer "F.Fab")
			(hide yes)
			(effects
				(font
					(size 1 1)
					(thickness 0.15)
				)
			)
		)
		(property "Manufacturer" ""
			(at 0 0 0)
			(layer "F.Fab")
			(hide yes)
			(effects
				(font
					(size 1 1)
					(thickness 0.15)
				)
			)
		)
		(property "exclude_from_bom" ""
			(at 0 0 0)
			(layer "F.Fab")
			(hide yes)
			(effects
				(font
					(size 1 1)
					(thickness 0.15)
				)
			)
		)
		(sheetfile "k410t-devboard.kicad_sch")
		(attr exclude_from_pos_files exclude_from_bom)
		(pad "1" thru_hole circle
			(at 0 0)
			(size 6 6)
			(drill 3)
			(layers "*.Cu" "*.Mask")
			(remove_unused_layers no)
			(net 1 "GND")
			(pintype "passive")
		)
	)
)
